# BASEBOARD_FAB2 (Tioga Pass) — schematic netlist excerpt (pin names and nets, part order shuffled) for the footprints in the layout excerpt that follows; sources: Cadence DE-HDL packaged netlist, KiCad conversion of Wiwynn_Tioga_Pass_MB.brd

C4E13  CAP_A  0.1UF 16V 10% X7R  pkg 0402V  page 214 : A = VR_FET_SW_P12V_STBY_PVCCIN_CPU0 ; B = GND
CT66  CAP_A  0.1UF 16V 10% X7R  pkg 0402V  page 236 : A = VR_PVNN_PCH_AIREF1 ; B = GND
C1E8  CAP  1.0UF 16V 10% X6S  pkg 0402  page 207 : A = VR_PVCCIN_CPU1_PH1_VCIN ; B = GND

(kicad_pcb
	(version 20260206)
	(generator "pcbnew")
	(generator_version "10.0")
	(general
		(thickness 1.6)
		(legacy_teardrops no)
	)
	(paper "A4")
	(title_block
		(title "Wiwynn_Tioga_Pass_MB.brd")
		(comment 1 "Tioga Pass / footprints 2032-2034 of 4770")
	)
	(layers
		(0 "F.Cu" signal "TOP")
		(4 "In1.Cu" signal "L2GND")
		(6 "In2.Cu" signal "L3")
		(8 "In3.Cu" signal "L4GND")
		(10 "In4.Cu" signal "L5")
		(12 "In5.Cu" signal "L6GND")
		(14 "In6.Cu" signal "L7VCC")
		(16 "In7.Cu" signal "L8VCC")
		(18 "In8.Cu" signal "L9GND")
		(20 "In9.Cu" signal "L10")
		(22 "In10.Cu" signal "L11GND")
		(24 "In11.Cu" signal "L12")
		(26 "In12.Cu" signal "L13GND")
		(2 "B.Cu" signal "BOTTOM")
		(9 "F.Adhes" user "F.Adhesive")
		(11 "B.Adhes" user "B.Adhesive")
		(13 "F.Paste" user "Package Geometry/Pastemask Top")
		(15 "B.Paste" user "Package Geometry/Pastemask Bottom")
		(5 "F.SilkS" user "Ref Des/Silkscreen Top")
		(7 "B.SilkS" user "Ref Des/Silkscreen Bottom")
		(1 "F.Mask" user "Board Geometry/Soldermask Top")
		(3 "B.Mask" user "Board Geometry/Soldermask Bottom")
		(17 "Dwgs.User" user "User.Drawings")
		(19 "Cmts.User" user "User.Comments")
		(21 "Eco1.User" user "User.Eco1")
		(23 "Eco2.User" user "User.Eco2")
		(25 "Edge.Cuts" user "Board Geometry/Outline")
		(27 "Margin" user)
		(31 "F.CrtYd" user "Package Geometry/Place Bound Top")
		(29 "B.CrtYd" user "Package Geometry/Place Bound Bottom")
		(35 "F.Fab" user "Ref Des/Assembly Top")
		(33 "B.Fab" user "Ref Des/Assembly Bottom")
	)
	(footprint ""
		(layer "F.Cu")
		(at 32.1564 -53.1368 -90)
		(property "Reference" "C1E8"
			(at 0 0 270)
			(layer "F.SilkS")
			(hide yes)
			(effects
				(font
					(size 1.27 1.27)
				)
			)
		)
		(property "Value" ""
			(at 0 0 270)
			(layer "F.Fab")
			(effects
				(font
					(size 1.27 1.27)
				)
			)
		)
		(duplicate_pad_numbers_are_jumpers no)
		(fp_rect
			(start 0.3048 0.9906)
			(end -0.3048 -0.1016)
			(stroke
				(width 0)
				(type default)
			)
			(fill no)
			(layer "F.CrtYd")
		)
		(fp_line
			(start -0.3048 0.9906)
			(end 0.3048 0.9906)
			(stroke
				(width 0.1)
				(type default)
			)
			(layer "F.Fab")
		)
		(fp_line
			(start 0.3048 0.9906)
			(end 0.3048 -0.1016)
			(stroke
				(width 0.1)
				(type default)
			)
			(layer "F.Fab")
		)
		(fp_line
			(start -0.3048 -0.1016)
			(end -0.3048 0.9906)
			(stroke
				(width 0.1)
				(type default)
			)
			(layer "F.Fab")
		)
		(fp_line
			(start 0.3048 -0.1016)
			(end -0.3048 -0.1016)
			(stroke
				(width 0.1)
				(type default)
			)
			(layer "F.Fab")
		)
		(pad "1" smd rect
			(at 0 0 270)
			(size 0.508 0.508)
			(layers "F.Cu" "F.Mask" "F.Paste")
			(net "VR_PVCCIN_CPU1_PH1_VCIN")
		)
		(pad "2" smd rect
			(at 0 0.889 270)
			(size 0.508 0.508)
			(layers "F.Cu" "F.Mask" "F.Paste")
			(net "GND")
		)
		(zone
			(layer "F.Cu")
			(hatch none 0.5)
			(connect_pads
				(clearance 0)
			)
			(min_thickness 0.25)
			(keepout
				(tracks not_allowed)
				(vias allowed)
				(pads allowed)
				(copperpour not_allowed)
				(footprints allowed)
			)
			(placement
				(enabled no)
				(sheetname "")
			)
			(fill
				(thermal_gap 0.5)
				(thermal_bridge_width 0.5)
				(island_removal_mode 0)
			)
			(polygon
				(pts
					(xy 31.5214 -52.8828) (xy 31.9024 -52.8828) (xy 31.9024 -53.3908) (xy 31.5214 -53.3908)
				)
			)
		)
		(zone
			(layer "F.Cu")
			(hatch none 0.5)
			(connect_pads
				(clearance 0)
			)
			(min_thickness 0.25)
			(keepout
				(tracks allowed)
				(vias not_allowed)
				(pads allowed)
				(copperpour not_allowed)
				(footprints allowed)
			)
			(placement
				(enabled no)
				(sheetname "")
			)
			(fill
				(thermal_gap 0.5)
				(thermal_bridge_width 0.5)
				(island_removal_mode 0)
			)
			(polygon
				(pts
					(xy 31.5214 -52.8828) (xy 31.9024 -52.8828) (xy 31.9024 -53.3908) (xy 31.5214 -53.3908)
				)
			)
		)
	)
	(footprint ""
		(layer "F.Cu")
		(at 177.994818 -51.051206 -90)
		(property "Reference" "C4E13"
			(at 0 0 270)
			(layer "F.SilkS")
			(hide yes)
			(effects
				(font
					(size 1.27 1.27)
				)
			)
		)
		(property "Value" ""
			(at 0 0 270)
			(layer "F.Fab")
			(effects
				(font
					(size 1.27 1.27)
				)
			)
		)
		(duplicate_pad_numbers_are_jumpers no)
		(fp_poly
			(pts
				(xy 0.3048 -0.1016) (xy 0.3048 0.9906) (xy -0.3048 0.9906) (xy -0.3048 -0.1016)
			)
			(stroke
				(width 0)
				(type default)
			)
			(fill no)
			(layer "F.CrtYd")
		)
		(fp_line
			(start -0.3048 0.9906)
			(end 0.3048 0.9906)
			(stroke
				(width 0.1)
				(type default)
			)
			(layer "F.Fab")
		)
		(fp_line
			(start 0.3048 0.9906)
			(end 0.3048 -0.1016)
			(stroke
				(width 0.1)
				(type default)
			)
			(layer "F.Fab")
		)
		(fp_line
			(start -0.3048 -0.1016)
			(end -0.3048 0.9906)
			(stroke
				(width 0.1)
				(type default)
			)
			(layer "F.Fab")
		)
		(fp_line
			(start 0.3048 -0.1016)
			(end -0.3048 -0.1016)
			(stroke
				(width 0.1)
				(type default)
			)
			(layer "F.Fab")
		)
		(pad "1" smd rect
			(at 0 0 270)
			(size 0.508 0.508)
			(layers "F.Cu" "F.Mask" "F.Paste")
			(net "VR_FET_SW_P12V_STBY_PVCCIN_CPU0")
		)
		(pad "2" smd rect
			(at 0 0.889 270)
			(size 0.508 0.508)
			(layers "F.Cu" "F.Mask" "F.Paste")
			(net "GND")
		)
		(zone
			(layer "F.Cu")
			(hatch none 0.5)
			(connect_pads
				(clearance 0)
			)
			(min_thickness 0.25)
			(keepout
				(tracks not_allowed)
				(vias allowed)
				(pads allowed)
				(copperpour not_allowed)
				(footprints allowed)
			)
			(placement
				(enabled no)
				(sheetname "")
			)
			(fill
				(thermal_gap 0.5)
				(thermal_bridge_width 0.5)
				(island_removal_mode 0)
			)
			(polygon
				(pts
					(xy 177.359818 -51.305206) (xy 177.359818 -50.797206) (xy 177.740818 -50.797206) (xy 177.740818 -51.305206)
				)
			)
		)
		(zone
			(layer "F.Cu")
			(hatch none 0.5)
			(connect_pads
				(clearance 0)
			)
			(min_thickness 0.25)
			(keepout
				(tracks allowed)
				(vias not_allowed)
				(pads allowed)
				(copperpour not_allowed)
				(footprints allowed)
			)
			(placement
				(enabled no)
				(sheetname "")
			)
			(fill
				(thermal_gap 0.5)
				(thermal_bridge_width 0.5)
				(island_removal_mode 0)
			)
			(polygon
				(pts
					(xy 177.740818 -51.305206) (xy 177.740818 -50.797206) (xy 177.359818 -50.797206) (xy 177.359818 -51.305206)
				)
			)
		)
	)
	(footprint ""
		(layer "F.Cu")
		(at 373.1006 -157.9118 -90)
		(property "Reference" "CT66"
			(at 5.79247 9.1694 0)
			(unlocked yes)
			(layer "F.SilkS")
			(effects
				(font
					(size 0.7874 0.5842)
					(thickness 0.1524)
				)
				(justify left)
			)
		)
		(property "Value" ""
			(at 0 0 270)
			(layer "F.Fab")
			(effects
				(font
					(size 1.27 1.27)
				)
			)
		)
		(duplicate_pad_numbers_are_jumpers no)
		(fp_poly
			(pts
				(xy 0.3048 -0.1016) (xy 0.3048 0.9906) (xy -0.3048 0.9906) (xy -0.3048 -0.1016)
			)
			(stroke
				(width 0)
				(type default)
			)
			(fill no)
			(layer "F.CrtYd")
		)
		(fp_line
			(start -0.3048 0.9906)
			(end 0.3048 0.9906)
			(stroke
				(width 0.1)
				(type default)
			)
			(layer "F.Fab")
		)
		(fp_line
			(start 0.3048 0.9906)
			(end 0.3048 -0.1016)
			(stroke
				(width 0.1)
				(type default)
			)
			(layer "F.Fab")
		)
		(fp_line
			(start -0.3048 -0.1016)
			(end -0.3048 0.9906)
			(stroke
				(width 0.1)
				(type default)
			)
			(layer "F.Fab")
		)
		(fp_line
			(start 0.3048 -0.1016)
			(end -0.3048 -0.1016)
			(stroke
				(width 0.1)
				(type default)
			)
			(layer "F.Fab")
		)
		(pad "1" smd rect
			(at 0 0 270)
			(size 0.508 0.508)
			(layers "F.Cu" "F.Mask" "F.Paste")
			(net "VR_PVNN_PCH_AIREF1")
		)
		(pad "2" smd rect
			(at 0 0.889 270)
			(size 0.508 0.508)
			(layers "F.Cu" "F.Mask" "F.Paste")
			(net "GND")
		)
		(zone
			(layer "F.Cu")
			(hatch none 0.5)
			(connect_pads
				(clearance 0)
			)
			(min_thickness 0.25)
			(keepout
				(tracks not_allowed)
				(vias allowed)
				(pads allowed)
				(copperpour not_allowed)
				(footprints allowed)
			)
			(placement
				(enabled no)
				(sheetname "")
			)
			(fill
				(thermal_gap 0.5)
				(thermal_bridge_width 0.5)
				(island_removal_mode 0)
			)
			(polygon
				(pts
					(xy 372.4656 -158.1658) (xy 372.4656 -157.6578) (xy 372.8466 -157.6578) (xy 372.8466 -158.1658)
				)
			)
		)
		(zone
			(layer "F.Cu")
			(hatch none 0.5)
			(connect_pads
				(clearance 0)
			)
			(min_thickness 0.25)
			(keepout
				(tracks allowed)
				(vias not_allowed)
				(pads allowed)
				(copperpour not_allowed)
				(footprints allowed)
			)
			(placement
				(enabled no)
				(sheetname "")
			)
			(fill
				(thermal_gap 0.5)
				(thermal_bridge_width 0.5)
				(island_removal_mode 0)
			)
			(polygon
				(pts
					(xy 372.8466 -158.1658) (xy 372.8466 -157.6578) (xy 372.4656 -157.6578) (xy 372.4656 -158.1658)
				)
			)
		)
	)
)
